FILE_TYPE = CONNECTIVITY;
{Allegro Design Entry HDL 16.6-p007 (v16-6-112F) 10/10/2012}
"PAGE_NUMBER" = 41;
0"NC";
1"GND\g";
2"GND\g";
3"GND\g";
4"GND\g";
5"GND\g";
6"GND\g";
7"GND\g";
8"GND\g";
%"GND"
"1","(-4475,550)","0","mstr_symbols","I275";
;
HDL_POWER"GND"
BODY_TYPE"PLUMBING"
CDS_LIB"mstr_symbols"
SIZE"1B"
VOLTAGE"0.0V";
"A\NAC"1;
%"GND"
"1","(-2800,525)","0","mstr_symbols","I276";
;
HDL_POWER"GND"
BODY_TYPE"PLUMBING"
CDS_LIB"mstr_symbols"
SIZE"1B"
VOLTAGE"0.0V";
"A\NAC"2;
%"GND"
"1","(-1075,475)","0","mstr_symbols","I277";
;
HDL_POWER"GND"
BODY_TYPE"PLUMBING"
CDS_LIB"mstr_symbols"
SIZE"1B"
VOLTAGE"0.0V";
"A\NAC"3;
%"GND"
"1","(-6025,550)","0","mstr_symbols","I278";
;
HDL_POWER"GND"
BODY_TYPE"PLUMBING"
CDS_LIB"mstr_symbols"
SIZE"1B"
VOLTAGE"0.0V";
"A\NAC"4;
%"GND"
"1","(-4350,550)","0","mstr_symbols","I279";
;
HDL_POWER"GND"
BODY_TYPE"PLUMBING"
CDS_LIB"mstr_symbols"
SIZE"1B"
VOLTAGE"0.0V";
"A\NAC"5;
%"GND"
"1","(-2625,500)","0","mstr_symbols","I280";
;
HDL_POWER"GND"
BODY_TYPE"PLUMBING"
CDS_LIB"mstr_symbols"
SIZE"1B"
VOLTAGE"0.0V";
"A\NAC"6;
%"GND"
"1","(-925,475)","0","mstr_symbols","I281";
;
HDL_POWER"GND"
BODY_TYPE"PLUMBING"
CDS_LIB"mstr_symbols"
SIZE"1B"
VOLTAGE"0.0V";
"A\NAC"7;
%"GND"
"1","(600,1650)","0","mstr_symbols","I282";
;
HDL_POWER"GND"
BODY_TYPE"PLUMBING"
CDS_LIB"mstr_symbols"
SIZE"1B"
VOLTAGE"0.0V";
"A\NAC"8;
%"SKX_EXT_B"
"27","(-5275,2650)","0","chpset_lib","I283";
;
CDS_SEC"27"
ROOM"CPU0"
CDS_LOCATION"U5D1"
SEC"27"
SEC_TYPE"BGA1"
CDS_LIB"chpset_lib"
PACK_TYPE"BGA1"
MATERIAL"IC"
PART_NUMBER"TBD"
LOCATION"U5D1";
"VSS<454>"
$PN"P49"1;
"VSS<455>"
$PN"CJ12"1;
"VSS<456>"
$PN"CJ10"1;
"VSS<457>"
$PN"CJ8"1;
"VSS<458>"
$PN"CJ6"1;
"VSS<459>"
$PN"CJ2"1;
"VSS<460>"
$PN"CH83"1;
"VSS<461>"
$PN"CH81"1;
"VSS<462>"
$PN"CH79"1;
"VSS<463>"
$PN"CH73"1;
"VSS<464>"
$PN"CH67"1;
"VSS<465>"
$PN"CH63"1;
"VSS<466>"
$PN"CH19"1;
"VSS<467>"
$PN"CH15"1;
"VSS<468>"
$PN"CH3"1;
"VSS<469>"
$PN"CH1"1;
"VSS<470>"
$PN"CG80"1;
"VSS<471>"
$PN"CG72"1;
"VSS<472>"
$PN"CG68"1;
"VSS<473>"
$PN"CG62"1;
"VSS<474>"
$PN"CG22"1;
"VSS<475>"
$PN"CG18"1;
"VSS<476>"
$PN"P51"1;
"VSS<477>"
$PN"CF83"1;
"VSS<478>"
$PN"CF77"1;
"VSS<479>"
$PN"CF71"1;
"VSS<480>"
$PN"CF69"1;
"VSS<481>"
$PN"CF63"1;
"VSS<482>"
$PN"CF9"1;
"VSS<483>"
$PN"P53"1;
"VSS<484>"
$PN"CE82"1;
"VSS<485>"
$PN"CE70"1;
"VSS<486>"
$PN"CE62"1;
"VSS<487>"
$PN"CE26"1;
"VSS<488>"
$PN"CE20"1;
"VSS<489>"
$PN"CE14"1;
"VSS<490>"
$PN"CE10"1;
"VSS<491>"
$PN"CD81"1;
"VSS<492>"
$PN"CD79"1;
"VSS<493>"
$PN"CD77"1;
"VSS<494>"
$PN"CD75"1;
"VSS<495>"
$PN"CD73"1;
"VSS<496>"
$PN"CD63"1;
"VSS<497>"
$PN"CD13"1;
"VSS<498>"
$PN"CD5"1;
"VSS<499>"
$PN"CC82"1;
"VSS<500>"
$PN"CC80"1;
"VSS<501>"
$PN"CC78"1;
"VSS<502>"
$PN"CC76"1;
"VSS<503>"
$PN"CC74"1;
"VSS<504>"
$PN"CC72"1;
"VSS<505>"
$PN"CC64"1;
"VSS<506>"
$PN"CC24"1;
"VSS<507>"
$PN"CC18"1;
"VSS<508>"
$PN"CC16"1;
"VSS<509>"
$PN"CC4"1;
"VSS<510>"
$PN"CB71"1;
"VSS<511>"
$PN"CB63"1;
"VSS<512>"
$PN"CB27"1;
"VSS<513>"
$PN"CB9"1;
"VSS<514>"
$PN"CB7"1;
"VSS<515>"
$PN"CA70"1;
"VSS<516>"
$PN"CA68"1;
"VSS<517>"
$PN"CA66"1;
"VSS<518>"
$PN"CA64"1;
"VSS<519>"
$PN"CA26"1;
"VSS<520>"
$PN"CA18"1;
"VSS<521>"
$PN"CA14"1;
"VSS<522>"
$PN"CA10"1;
"VSS<523>"
$PN"CA8"1;
"VSS<524>"
$PN"CA6"1;
"VSS<525>"
$PN"CA2"1;
"VSS<526>"
$PN"BY71"1;
"VSS<527>"
$PN"BY69"1;
"VSS<528>"
$PN"BY67"1;
"VSS<529>"
$PN"BY65"1;
"VSS<530>"
$PN"BY63"1;
"VSS<531>"
$PN"BY23"1;
"VSS<532>"
$PN"BY13"1;
"VSS<533>"
$PN"BY11"1;
"VSS<534>"
$PN"BW82"4;
"VSS<535>"
$PN"BW80"4;
"VSS<536>"
$PN"BW78"4;
"VSS<537>"
$PN"BW76"4;
"VSS<538>"
$PN"BW74"4;
"VSS<539>"
$PN"BW72"4;
"VSS<540>"
$PN"BW26"4;
"VSS<541>"
$PN"BW18"4;
"VSS<542>"
$PN"BW16"4;
"VSS<543>"
$PN"BW14"4;
"VSS<544>"
$PN"BW12"4;
"VSS<545>"
$PN"P55"4;
"VSS<546>"
$PN"BW6"4;
"VSS<547>"
$PN"BV25"4;
"VSS<548>"
$PN"BV17"4;
"VSS<549>"
$PN"BU10"4;
"VSS<550>"
$PN"BV5"4;
"VSS<551>"
$PN"BU8"4;
"VSS<552>"
$PN"BT25"4;
"VSS<553>"
$PN"BT23"4;
"VSS<554>"
$PN"BT21"4;
"VSS<555>"
$PN"BT5"4;
"VSS<556>"
$PN"BT3"4;
"VSS<557>"
$PN"BR82"4;
"VSS<558>"
$PN"BR80"4;
"VSS<559>"
$PN"BR78"4;
"VSS<560>"
$PN"BR76"4;
"VSS<561>"
$PN"BR74"4;
"VSS<562>"
$PN"BR72"4;
"VSS<563>"
$PN"BR70"4;
"VSS<564>"
$PN"BR68"4;
"VSS<565>"
$PN"BR66"4;
"VSS<566>"
$PN"BR64"4;
"VSS<567>"
$PN"P57"4;
"VSS<568>"
$PN"BR16"4;
"VSS<569>"
$PN"BR10"4;
"VSS<570>"
$PN"BR6"4;
"VSS<571>"
$PN"BP27"4;
"VSS<572>"
$PN"BP3"4;
"VSS<573>"
$PN"BN26"4;
"VSS<574>"
$PN"BN20"4;
"VSS<575>"
$PN"BN10"4;
"VSS<576>"
$PN"BN6"4;
"VSS<577>"
$PN"BM25"4;
"VSS<578>"
$PN"P59"4;
"VSS<579>"
$PN"BM15"4;
"VSS<580>"
$PN"BM13"4;
"VSS<581>"
$PN"BM9"4;
"VSS<582>"
$PN"BL82"4;
"VSS<583>"
$PN"BL80"4;
"VSS<584>"
$PN"BL78"4;
"VSS<585>"
$PN"BL76"4;
"VSS<586>"
$PN"BL74"4;
"VSS<587>"
$PN"BL72"4;
"VSS<588>"
$PN"BL70"4;
"VSS<589>"
$PN"BL68"4;
"VSS<590>"
$PN"BL66"4;
"VSS<591>"
$PN"BL64"4;
"VSS<592>"
$PN"BL24"4;
"VSS<593>"
$PN"BL22"4;
"VSS<594>"
$PN"P61"4;
"VSS<595>"
$PN"BL12"4;
"VSS<596>"
$PN"BL10"4;
"VSS<597>"
$PN"BL6"4;
"VSS<598>"
$PN"BK19"4;
"VSS<599>"
$PN"BK11"4;
"VSS<600>"
$PN"BK7"4;
"VSS<601>"
$PN"BK3"4;
"VSS<602>"
$PN"BJ6"4;
"VSS<603>"
$PN"BJ4"4;
"VSS<604>"
$PN"BH21"4;
"VSS<605>"
$PN"BH15"4;
"VSS<606>"
$PN"BH11"4;
"VSS<607>"
$PN"BH9"4;
"VSS<608>"
$PN"BH7"4;
"VSS<609>"
$PN"BG82"4;
"VSS<610>"
$PN"BG80"4;
"VSS<611>"
$PN"BG78"4;
"VSS<612>"
$PN"BG76"4;
"VSS<613>"
$PN"BG74"4;
%"SKX_EXT_B"
"28","(-3575,2650)","0","chpset_lib","I284";
;
CDS_SEC"28"
ROOM"CPU0"
CDS_LOCATION"U5D1"
SEC"28"
SEC_TYPE"BGA1"
CDS_LIB"chpset_lib"
PACK_TYPE"BGA1"
MATERIAL"IC"
PART_NUMBER"TBD"
LOCATION"U5D1";
"VSS<294>"
$PN"DA46"2;
"VSS<295>"
$PN"DA44"2;
"VSS<296>"
$PN"DA38"2;
"VSS<297>"
$PN"DA36"2;
"VSS<298>"
$PN"DA34"2;
"VSS<299>"
$PN"DA32"2;
"VSS<300>"
$PN"DA30"2;
"VSS<301>"
$PN"DA28"2;
"VSS<302>"
$PN"DA26"2;
"VSS<303>"
$PN"DA18"2;
"VSS<304>"
$PN"H53"2;
"VSS<305>"
$PN"DA6"2;
"VSS<306>"
$PN"CY85"2;
"VSS<307>"
$PN"CY83"2;
"VSS<308>"
$PN"CY77"2;
"VSS<309>"
$PN"CY75"2;
"VSS<310>"
$PN"CY69"2;
"VSS<311>"
$PN"CY65"2;
"VSS<312>"
$PN"CY61"2;
"VSS<313>"
$PN"CY59"2;
"VSS<314>"
$PN"CY51"2;
"VSS<315>"
$PN"CY45"2;
"VSS<316>"
$PN"CY41"2;
"VSS<317>"
$PN"CY21"2;
"VSS<318>"
$PN"CY15"2;
"VSS<319>"
$PN"CY13"2;
"VSS<320>"
$PN"CY9"2;
"VSS<321>"
$PN"CY1"2;
"VSS<322>"
$PN"CW82"2;
"VSS<323>"
$PN"CW78"2;
"VSS<324>"
$PN"CW74"2;
"VSS<325>"
$PN"CW68"2;
"VSS<326>"
$PN"CW66"2;
"VSS<327>"
$PN"CW64"2;
"VSS<328>"
$PN"CW54"2;
"VSS<329>"
$PN"CW52"2;
"VSS<330>"
$PN"CW42"2;
"VSS<331>"
$PN"CW40"2;
"VSS<332>"
$PN"CW38"2;
"VSS<333>"
$PN"CW32"2;
"VSS<334>"
$PN"CW26"2;
"VSS<335>"
$PN"CW12"2;
"VSS<336>"
$PN"CV83"2;
"VSS<337>"
$PN"CV81"2;
"VSS<338>"
$PN"CV79"2;
"VSS<339>"
$PN"CV73"2;
"VSS<340>"
$PN"CV67"2;
"VSS<341>"
$PN"CV63"2;
"VSS<342>"
$PN"CV55"2;
"VSS<343>"
$PN"CV53"2;
"VSS<344>"
$PN"CV41"2;
"VSS<345>"
$PN"CV39"2;
"VSS<346>"
$PN"CV37"2;
"VSS<347>"
$PN"CV33"2;
"VSS<348>"
$PN"CV31"2;
"VSS<349>"
$PN"CV27"2;
"VSS<350>"
$PN"CV25"2;
"VSS<351>"
$PN"CV17"2;
"VSS<352>"
$PN"H55"2;
"VSS<353>"
$PN"CV1"2;
"VSS<354>"
$PN"CU86"2;
"VSS<355>"
$PN"CU82"2;
"VSS<356>"
$PN"CU80"2;
"VSS<357>"
$PN"CU78"2;
"VSS<358>"
$PN"CU76"2;
"VSS<359>"
$PN"CU68"2;
"VSS<360>"
$PN"CU62"2;
"VSS<361>"
$PN"CU56"2;
"VSS<362>"
$PN"CU36"2;
"VSS<363>"
$PN"CU34"2;
"VSS<364>"
$PN"CU30"2;
"VSS<365>"
$PN"CU28"2;
"VSS<366>"
$PN"CU22"2;
"VSS<367>"
$PN"CU4"2;
"VSS<368>"
$PN"CT85"2;
"VSS<369>"
$PN"CT83"2;
"VSS<370>"
$PN"CT79"2;
"VSS<371>"
$PN"CT73"2;
"VSS<372>"
$PN"CT57"2;
"VSS<373>"
$PN"CT35"2;
"VSS<374>"
$PN"CT33"5;
"VSS<375>"
$PN"CT29"5;
"VSS<376>"
$PN"CT27"5;
"VSS<377>"
$PN"CT19"5;
"VSS<378>"
$PN"CT13"5;
"VSS<379>"
$PN"H57"5;
"VSS<380>"
$PN"CR86"5;
"VSS<381>"
$PN"CR78"5;
"VSS<382>"
$PN"CR68"5;
"VSS<383>"
$PN"CR66"5;
"VSS<384>"
$PN"CR64"5;
"VSS<385>"
$PN"CR62"5;
"VSS<386>"
$PN"CR58"5;
"VSS<387>"
$PN"CR32"5;
"VSS<388>"
$PN"CR24"5;
"VSS<389>"
$PN"CR22"5;
"VSS<390>"
$PN"CR10"5;
"VSS<391>"
$PN"CR6"5;
"VSS<392>"
$PN"CP83"5;
"VSS<393>"
$PN"CP81"5;
"VSS<394>"
$PN"CP75"5;
"VSS<395>"
$PN"CP73"5;
"VSS<396>"
$PN"CP69"5;
"VSS<397>"
$PN"CP59"5;
"VSS<398>"
$PN"CP25"5;
"VSS<399>"
$PN"H59"5;
"VSS<400>"
$PN"CP1"5;
"VSS<401>"
$PN"CN78"5;
"VSS<402>"
$PN"CN68"5;
"VSS<403>"
$PN"CN62"5;
"VSS<404>"
$PN"CN60"5;
"VSS<405>"
$PN"CN32"5;
"VSS<406>"
$PN"CN26"5;
"VSS<407>"
$PN"H61"5;
"VSS<408>"
$PN"CN12"5;
"VSS<409>"
$PN"CN2"5;
"VSS<410>"
$PN"CM85"5;
"VSS<411>"
$PN"CM83"5;
"VSS<412>"
$PN"CM77"5;
"VSS<413>"
$PN"CM73"5;
"VSS<414>"
$PN"CM67"5;
"VSS<415>"
$PN"CM63"5;
"VSS<416>"
$PN"CM61"5;
"VSS<417>"
$PN"CM31"5;
"VSS<418>"
$PN"CM5"5;
"VSS<419>"
$PN"CM29"5;
"VSS<420>"
$PN"CM19"5;
"VSS<421>"
$PN"CL80"5;
"VSS<422>"
$PN"CL78"5;
"VSS<423>"
$PN"CL76"5;
"VSS<424>"
$PN"CL74"5;
"VSS<425>"
$PN"CL66"5;
"VSS<426>"
$PN"CL64"5;
"VSS<427>"
$PN"CL62"5;
"VSS<428>"
$PN"H63"5;
"VSS<429>"
$PN"P45"5;
"VSS<430>"
$PN"CL18"5;
"VSS<431>"
$PN"CL14"5;
"VSS<432>"
$PN"CL8"5;
"VSS<433>"
$PN"CK85"5;
"VSS<434>"
$PN"CK83"5;
"VSS<435>"
$PN"CK75"5;
"VSS<436>"
$PN"CK73"5;
"VSS<437>"
$PN"CK71"5;
"VSS<438>"
$PN"CK69"5;
"VSS<439>"
$PN"CK67"5;
"VSS<440>"
$PN"CK65"5;
"VSS<441>"
$PN"CK63"5;
"VSS<442>"
$PN"CK27"5;
"VSS<443>"
$PN"CK21"5;
"VSS<444>"
$PN"CK15"5;
"VSS<445>"
$PN"CK11"5;
"VSS<446>"
$PN"CJ86"5;
"VSS<447>"
$PN"CJ84"5;
"VSS<448>"
$PN"CJ82"5;
"VSS<449>"
$PN"CJ78"5;
"VSS<450>"
$PN"CJ76"5;
"VSS<451>"
$PN"CJ74"5;
"VSS<452>"
$PN"CJ62"5;
"VSS<453>"
$PN"P47"5;
%"SKX_EXT_B"
"29","(-1850,2600)","0","chpset_lib","I285";
;
CDS_SEC"29"
ROOM"CPU0"
CDS_LOCATION"U5D1"
SEC"29"
SEC_TYPE"BGA1"
CDS_LIB"chpset_lib"
PACK_TYPE"BGA1"
MATERIAL"IC"
PART_NUMBER"TBD"
LOCATION"U5D1";
"VSS<134>"
$PN"DN72"3;
"VSS<135>"
$PN"DN68"3;
"VSS<136>"
$PN"DN38"3;
"VSS<137>"
$PN"DN32"3;
"VSS<138>"
$PN"DN26"3;
"VSS<139>"
$PN"DN22"3;
"VSS<140>"
$PN"DN12"3;
"VSS<141>"
$PN"BH17"3;
"VSS<142>"
$PN"DN2"3;
"VSS<143>"
$PN"DM83"3;
"VSS<144>"
$PN"DM77"3;
"VSS<145>"
$PN"DM73"3;
"VSS<146>"
$PN"DM65"3;
"VSS<147>"
$PN"DM39"3;
"VSS<148>"
$PN"DM37"3;
"VSS<149>"
$PN"DM33"3;
"VSS<150>"
$PN"DM31"3;
"VSS<151>"
$PN"DM27"3;
"VSS<152>"
$PN"DM25"3;
"VSS<153>"
$PN"H45"3;
"VSS<154>"
$PN"DM15"3;
"VSS<155>"
$PN"DL80"3;
"VSS<156>"
$PN"DL78"3;
"VSS<157>"
$PN"DL76"3;
"VSS<158>"
$PN"DL74"3;
"VSS<159>"
$PN"DL70"3;
"VSS<160>"
$PN"DL68"3;
"VSS<161>"
$PN"DL40"3;
"VSS<162>"
$PN"DL36"3;
"VSS<163>"
$PN"DL34"3;
"VSS<164>"
$PN"DL30"3;
"VSS<165>"
$PN"DL28"3;
"VSS<166>"
$PN"DL24"3;
"VSS<167>"
$PN"DL22"3;
"VSS<168>"
$PN"DL4"3;
"VSS<169>"
$PN"DL18"3;
"VSS<170>"
$PN"DL16"3;
"VSS<171>"
$PN"DK85"3;
"VSS<172>"
$PN"DK83"3;
"VSS<173>"
$PN"DK77"3;
"VSS<174>"
$PN"DK75"3;
"VSS<175>"
$PN"DK73"3;
"VSS<176>"
$PN"DK41"3;
"VSS<177>"
$PN"DK39"3;
"VSS<178>"
$PN"DK35"3;
"VSS<179>"
$PN"DK29"3;
"VSS<180>"
$PN"DK23"3;
"VSS<181>"
$PN"DK7"3;
"VSS<182>"
$PN"DJ84"3;
"VSS<183>"
$PN"DJ82"3;
"VSS<184>"
$PN"DJ78"3;
"VSS<185>"
$PN"DJ74"3;
"VSS<186>"
$PN"DJ68"3;
"VSS<187>"
$PN"DJ42"3;
"VSS<188>"
$PN"DJ38"3;
"VSS<189>"
$PN"DJ22"3;
"VSS<190>"
$PN"H47"3;
"VSS<191>"
$PN"DJ10"3;
"VSS<192>"
$PN"DJ2"3;
"VSS<193>"
$PN"DH83"3;
"VSS<194>"
$PN"DH81"3;
"VSS<195>"
$PN"DH79"3;
"VSS<196>"
$PN"DH73"3;
"VSS<197>"
$PN"DH71"3;
"VSS<198>"
$PN"DH67"3;
"VSS<199>"
$PN"DH41"3;
"VSS<200>"
$PN"DH37"3;
"VSS<201>"
$PN"DH35"3;
"VSS<202>"
$PN"DH33"3;
"VSS<203>"
$PN"DH31"3;
"VSS<204>"
$PN"DH29"3;
"VSS<205>"
$PN"DH27"3;
"VSS<206>"
$PN"DH25"3;
"VSS<207>"
$PN"DH23"3;
"VSS<208>"
$PN"DH15"3;
"VSS<209>"
$PN"DH13"3;
"VSS<210>"
$PN"DG82"3;
"VSS<211>"
$PN"DG80"3;
"VSS<212>"
$PN"DG78"3;
"VSS<213>"
$PN"DG76"3;
"VSS<214>"
$PN"DG68"6;
"VSS<215>"
$PN"DG66"6;
"VSS<216>"
$PN"DG24"6;
"VSS<217>"
$PN"DG16"6;
"VSS<218>"
$PN"DG14"6;
"VSS<219>"
$PN"H49"6;
"VSS<220>"
$PN"DG2"6;
"VSS<221>"
$PN"DF85"6;
"VSS<222>"
$PN"DF83"6;
"VSS<223>"
$PN"DF79"6;
"VSS<224>"
$PN"DF73"6;
"VSS<225>"
$PN"DF69"6;
"VSS<226>"
$PN"DF65"6;
"VSS<227>"
$PN"DF41"6;
"VSS<228>"
$PN"DF39"6;
"VSS<229>"
$PN"DF37"6;
"VSS<230>"
$PN"DF35"6;
"VSS<231>"
$PN"DF29"6;
"VSS<232>"
$PN"DF19"6;
"VSS<233>"
$PN"H51"6;
"VSS<234>"
$PN"DF7"6;
"VSS<235>"
$PN"DF5"6;
"VSS<236>"
$PN"DE78"6;
"VSS<237>"
$PN"DE72"6;
"VSS<238>"
$PN"DE70"6;
"VSS<239>"
$PN"DE64"6;
"VSS<240>"
$PN"DE36"6;
"VSS<241>"
$PN"DE34"6;
"VSS<242>"
$PN"DE30"6;
"VSS<243>"
$PN"DE28"6;
"VSS<244>"
$PN"DE24"6;
"VSS<245>"
$PN"DE20"6;
"VSS<246>"
$PN"DE18"6;
"VSS<247>"
$PN"DE8"6;
"VSS<248>"
$PN"DE6"6;
"VSS<249>"
$PN"DD83"6;
"VSS<250>"
$PN"DD81"6;
"VSS<251>"
$PN"DD75"6;
"VSS<252>"
$PN"DD73"6;
"VSS<253>"
$PN"DD71"6;
"VSS<254>"
$PN"DD37"6;
"VSS<255>"
$PN"DD33"6;
"VSS<256>"
$PN"DD31"6;
"VSS<257>"
$PN"DD27"6;
"VSS<258>"
$PN"DD23"6;
"VSS<259>"
$PN"DD11"6;
"VSS<260>"
$PN"DC86"6;
"VSS<261>"
$PN"DC84"6;
"VSS<262>"
$PN"DC78"6;
"VSS<263>"
$PN"DC70"6;
"VSS<264>"
$PN"DC68"6;
"VSS<265>"
$PN"DC66"6;
"VSS<266>"
$PN"DC64"6;
"VSS<267>"
$PN"DC42"6;
"VSS<268>"
$PN"DC38"6;
"VSS<269>"
$PN"DC32"6;
"VSS<270>"
$PN"DC26"6;
"VSS<271>"
$PN"DC24"6;
"VSS<272>"
$PN"DC14"6;
"VSS<273>"
$PN"DB85"6;
"VSS<274>"
$PN"DB83"6;
"VSS<275>"
$PN"DB77"6;
"VSS<276>"
$PN"DB73"6;
"VSS<277>"
$PN"DB49"6;
"VSS<278>"
$PN"DB47"6;
"VSS<279>"
$PN"DB41"6;
"VSS<280>"
$PN"DB39"6;
"VSS<281>"
$PN"DB25"6;
"VSS<282>"
$PN"DB23"6;
"VSS<283>"
$PN"DB17"6;
"VSS<284>"
$PN"DB13"6;
"VSS<285>"
$PN"DB3"6;
"VSS<286>"
$PN"DA80"6;
"VSS<287>"
$PN"DA78"6;
"VSS<288>"
$PN"DA76"6;
"VSS<289>"
$PN"DA74"6;
"VSS<290>"
$PN"DA70"6;
"VSS<291>"
$PN"DA64"6;
"VSS<292>"
$PN"DA50"6;
"VSS<293>"
$PN"DA48"6;
%"SKX_EXT_B"
"30","(-175,2650)","0","chpset_lib","I286";
;
CDS_SEC"30"
ROOM"CPU0"
CDS_LOCATION"U5D1"
SEC"30"
SEC_TYPE"BGA1"
CDS_LIB"chpset_lib"
PACK_TYPE"BGA1"
MATERIAL"IC"
PART_NUMBER"TBD"
LOCATION"U5D1";
"VSS<0>"
$PN"EF79"8;
"VSS<1>"
$PN"EF75"8;
"VSS<2>"
$PN"EF71"8;
"VSS<3>"
$PN"EE78"8;
"VSS<4>"
$PN"EE76"8;
"VSS<5>"
$PN"EE70"8;
"VSS<6>"
$PN"EE36"8;
"VSS<7>"
$PN"EE34"8;
"VSS<8>"
$PN"EE30"8;
"VSS<9>"
$PN"EE28"8;
"VSS<10>"
$PN"EE24"8;
"VSS<11>"
$PN"ED77"8;
"VSS<12>"
$PN"ED35"8;
"VSS<13>"
$PN"ED29"8;
"VSS<14>"
$PN"ED23"8;
"VSS<15>"
$PN"ED15"8;
"VSS<16>"
$PN"ED11"8;
"VSS<17>"
$PN"EC76"8;
"VSS<18>"
$PN"EC74"8;
"VSS<19>"
$PN"EC72"8;
"VSS<20>"
$PN"EC70"8;
"VSS<21>"
$PN"EC10"8;
"VSS<22>"
$PN"EB69"8;
"VSS<23>"
$PN"EB65"8;
"VSS<24>"
$PN"EB41"8;
"VSS<25>"
$PN"EB39"8;
"VSS<26>"
$PN"EB37"8;
"VSS<27>"
$PN"EB35"8;
"VSS<28>"
$PN"EB33"8;
"VSS<29>"
$PN"EB31"8;
"VSS<30>"
$PN"EB29"8;
"VSS<31>"
$PN"EB27"8;
"VSS<32>"
$PN"EB25"8;
"VSS<33>"
$PN"EB23"8;
"VSS<34>"
$PN"BR18"8;
"VSS<35>"
$PN"EB13"8;
"VSS<36>"
$PN"EA82"8;
"VSS<37>"
$PN"EA80"8;
"VSS<38>"
$PN"EA78"8;
"VSS<39>"
$PN"EA76"8;
"VSS<40>"
$PN"EA70"8;
"VSS<41>"
$PN"EA64"8;
"VSS<42>"
$PN"EA42"8;
"VSS<43>"
$PN"EA22"8;
"VSS<44>"
$PN"EA20"8;
"VSS<45>"
$PN"EA16"8;
"VSS<46>"
$PN"J16"8;
"VSS<47>"
$PN"EA6"8;
"VSS<48>"
$PN"DY75"8;
"VSS<49>"
$PN"DY71"8;
"VSS<50>"
$PN"DY41"8;
"VSS<51>"
$PN"DY35"8;
"VSS<52>"
$PN"DY29"8;
"VSS<53>"
$PN"DY23"8;
"VSS<54>"
$PN"DY19"7;
"VSS<55>"
$PN"DY5"7;
"VSS<56>"
$PN"DW84"7;
"VSS<57>"
$PN"DW82"7;
"VSS<58>"
$PN"DW8"7;
"VSS<59>"
$PN"DW76"7;
"VSS<60>"
$PN"DW74"7;
"VSS<61>"
$PN"DW72"7;
"VSS<62>"
$PN"DW70"7;
"VSS<63>"
$PN"DW68"7;
"VSS<64>"
$PN"DW66"7;
"VSS<65>"
$PN"DW64"7;
"VSS<66>"
$PN"DW40"7;
"VSS<67>"
$PN"DW36"7;
"VSS<68>"
$PN"DW34"7;
"VSS<69>"
$PN"DW30"7;
"VSS<70>"
$PN"DW28"7;
"VSS<71>"
$PN"DW24"7;
"VSS<72>"
$PN"DW20"7;
"VSS<73>"
$PN"DW12"7;
"VSS<74>"
$PN"DV81"7;
"VSS<75>"
$PN"DV77"7;
"VSS<76>"
$PN"DV73"7;
"VSS<77>"
$PN"DV39"7;
"VSS<78>"
$PN"DV37"7;
"VSS<79>"
$PN"DV33"7;
"VSS<80>"
$PN"DV31"7;
"VSS<81>"
$PN"DV27"7;
"VSS<82>"
$PN"DV25"7;
"VSS<83>"
$PN"DV21"7;
"VSS<84>"
$PN"DU84"7;
"VSS<85>"
$PN"DU82"7;
"VSS<86>"
$PN"DU80"7;
"VSS<87>"
$PN"DU78"7;
"VSS<88>"
$PN"DU72"7;
"VSS<89>"
$PN"DU70"7;
"VSS<90>"
$PN"DU38"7;
"VSS<91>"
$PN"DU32"7;
"VSS<92>"
$PN"DU26"7;
"VSS<93>"
$PN"DU22"7;
"VSS<94>"
$PN"CN14"7;
"VSS<95>"
$PN"DU14"7;
"VSS<96>"
$PN"DU10"7;
"VSS<97>"
$PN"DT85"7;
"VSS<98>"
$PN"DT83"7;
"VSS<99>"
$PN"DT79"7;
"VSS<100>"
$PN"DT69"7;
"VSS<101>"
$PN"DT65"7;
"VSS<102>"
$PN"DH21"7;
"VSS<103>"
$PN"DT17"7;
"VSS<104>"
$PN"DT3"7;
"VSS<105>"
$PN"DR78"7;
"VSS<106>"
$PN"DR76"7;
"VSS<107>"
$PN"DR74"7;
"VSS<108>"
$PN"DR72"7;
"VSS<109>"
$PN"DR70"7;
"VSS<110>"
$PN"DR68"7;
"VSS<111>"
$PN"DR66"7;
"VSS<112>"
$PN"DR42"7;
"VSS<113>"
$PN"DR40"7;
"VSS<114>"
$PN"DR38"7;
"VSS<115>"
$PN"DR36"7;
"VSS<116>"
$PN"DR34"7;
"VSS<117>"
$PN"DR32"7;
"VSS<118>"
$PN"DR30"7;
"VSS<119>"
$PN"DR28"7;
"VSS<120>"
$PN"DR26"7;
"VSS<121>"
$PN"DR24"7;
"VSS<122>"
$PN"DR22"7;
"VSS<123>"
$PN"DR20"7;
"VSS<124>"
$PN"CL22"7;
"VSS<125>"
$PN"CA20"7;
"VSS<126>"
$PN"DR6"7;
"VSS<127>"
$PN"BR26"7;
"VSS<128>"
$PN"DP83"7;
"VSS<129>"
$PN"DP81"7;
"VSS<130>"
$PN"DP71"7;
"VSS<131>"
$PN"DP69"7;
"VSS<132>"
$PN"DP67"7;
"VSS<133>"
$PN"DN78"7;
END.
